(kicad_pcb
	(version 20260206)
	(generator "pcbnew")
	(generator_version "10.0")
	(general
		(thickness 1.6)
		(legacy_teardrops no)
	)
	(paper "A4")
	(title_block
		(title "01162023_DA0F0TEBIF0_F0T_Expander_BD_F_brd_V02_OCP.brd")
		(comment 1 "Grand Teton / footprints 5850-5851 of 9728")
	)
	(layers
		(0 "F.Cu" signal "TOP")
		(4 "In1.Cu" signal "GND")
		(6 "In2.Cu" signal "VCC")
		(8 "In3.Cu" signal "VCC1")
		(10 "In4.Cu" signal "GND1")
		(12 "In5.Cu" signal "IN1")
		(14 "In6.Cu" signal "GND2")
		(16 "In7.Cu" signal "IN2")
		(18 "In8.Cu" signal "GND3")
		(20 "In9.Cu" signal "IN3")
		(22 "In10.Cu" signal "GND4")
		(24 "In11.Cu" signal "IN4")
		(26 "In12.Cu" signal "GND5")
		(28 "In13.Cu" signal "IN5")
		(30 "In14.Cu" signal "GND6")
		(32 "In15.Cu" signal "IN6")
		(34 "In16.Cu" signal "GND7")
		(2 "B.Cu" signal "BOTTOM")
		(9 "F.Adhes" user "F.Adhesive")
		(11 "B.Adhes" user "B.Adhesive")
		(13 "F.Paste" user "Package Geometry/Pastemask Top")
		(15 "B.Paste" user "Package Geometry/Pastemask Bottom")
		(5 "F.SilkS" user "Ref Des/Silkscreen Top")
		(7 "B.SilkS" user "Ref Des/Silkscreen Bottom")
		(1 "F.Mask" user "Board Geometry/Soldermask Top")
		(3 "B.Mask" user "Board Geometry/Soldermask Bottom")
		(17 "Dwgs.User" user "User.Drawings")
		(19 "Cmts.User" user "User.Comments")
		(21 "Eco1.User" user "User.Eco1")
		(23 "Eco2.User" user "User.Eco2")
		(25 "Edge.Cuts" user "Board Geometry/Outline")
		(27 "Margin" user)
		(31 "F.CrtYd" user "Package Geometry/Place Bound Top")
		(29 "B.CrtYd" user "Package Geometry/Place Bound Bottom")
		(35 "F.Fab" user "Ref Des/Assembly Top")
		(33 "B.Fab" user "Ref Des/Assembly Bottom")
	)
	(footprint ""
		(layer "F.Cu")
		(at 446.099438 -258.331208 -90)
		(property "Reference" "R6559"
			(at 0 0 270)
			(layer "F.SilkS")
			(hide yes)
			(effects
				(font
					(size 1.27 1.27)
				)
			)
		)
		(property "Value" ""
			(at 0 0 270)
			(layer "F.Fab")
			(effects
				(font
					(size 1.27 1.27)
				)
			)
		)
		(duplicate_pad_numbers_are_jumpers no)
		(fp_line
			(start -0.7874 0.4064)
			(end -0.7874 -0.4064)
			(stroke
				(width 0.1524)
				(type default)
			)
			(layer "F.SilkS")
		)
		(fp_line
			(start 0.7874 0.4064)
			(end -0.7874 0.4064)
			(stroke
				(width 0.1524)
				(type default)
			)
			(layer "F.SilkS")
		)
		(fp_line
			(start -0.7874 -0.4064)
			(end 0.7874 -0.4064)
			(stroke
				(width 0.1524)
				(type default)
			)
			(layer "F.SilkS")
		)
		(fp_line
			(start 0.7874 -0.4064)
			(end 0.7874 0.4064)
			(stroke
				(width 0.1524)
				(type default)
			)
			(layer "F.SilkS")
		)
		(fp_line
			(start -0.67945 0.3048)
			(end -0.67945 -0.305054)
			(stroke
				(width 0.1)
				(type default)
			)
			(layer "F.Fab")
		)
		(fp_line
			(start -0.12065 0.3048)
			(end -0.67945 0.3048)
			(stroke
				(width 0.1)
				(type default)
			)
			(layer "F.Fab")
		)
		(fp_line
			(start 0.120396 0.3048)
			(end 0.120396 0.2794)
			(stroke
				(width 0.1)
				(type default)
			)
			(layer "F.Fab")
		)
		(fp_line
			(start 0.67945 0.3048)
			(end 0.120396 0.3048)
			(stroke
				(width 0.1)
				(type default)
			)
			(layer "F.Fab")
		)
		(fp_line
			(start -0.12065 0.2794)
			(end -0.12065 0.3048)
			(stroke
				(width 0.1)
				(type default)
			)
			(layer "F.Fab")
		)
		(fp_line
			(start 0.120396 0.2794)
			(end -0.12065 0.2794)
			(stroke
				(width 0.1)
				(type default)
			)
			(layer "F.Fab")
		)
		(fp_line
			(start -0.12065 -0.2794)
			(end 0.12065 -0.2794)
			(stroke
				(width 0.1)
				(type default)
			)
			(layer "F.Fab")
		)
		(fp_line
			(start 0.12065 -0.2794)
			(end 0.12065 -0.3048)
			(stroke
				(width 0.1)
				(type default)
			)
			(layer "F.Fab")
		)
		(fp_line
			(start 0.12065 -0.3048)
			(end 0.67945 -0.3048)
			(stroke
				(width 0.1)
				(type default)
			)
			(layer "F.Fab")
		)
		(fp_line
			(start 0.67945 -0.3048)
			(end 0.67945 0.3048)
			(stroke
				(width 0.1)
				(type default)
			)
			(layer "F.Fab")
		)
		(fp_line
			(start -0.67945 -0.305054)
			(end -0.12065 -0.305054)
			(stroke
				(width 0.1)
				(type default)
			)
			(layer "F.Fab")
		)
		(fp_line
			(start -0.12065 -0.305054)
			(end -0.12065 -0.2794)
			(stroke
				(width 0.1)
				(type default)
			)
			(layer "F.Fab")
		)
		(pad "1" smd circle
			(at -0.40005 0 270)
			(size 0 0)
			(layers "F.Cu" "F.Mask" "F.Paste")
			(net "P1V25_SERDES_VDDPLL_PEX3")
		)
		(pad "2" smd circle
			(at 0.40005 0 270)
			(size 0 0)
			(layers "F.Cu" "F.Mask" "F.Paste")
			(net "P1V25_SERDES_VDDPLL_PEX3_C6")
		)
	)
	(footprint ""
		(layer "F.Cu")
		(at 38.96487 -26.785062 180)
		(property "Reference" "J31"
			(at 3.8608 -10.884662 90)
			(unlocked yes)
			(layer "F.SilkS")
			(effects
				(font
					(size 0.7874 0.5842)
					(thickness 0.1524)
				)
			)
		)
		(property "Value" ""
			(at 0 0 180)
			(layer "F.Fab")
			(effects
				(font
					(size 1.27 1.27)
				)
			)
		)
		(duplicate_pad_numbers_are_jumpers no)
		(fp_line
			(start 3.150108 12.115038)
			(end 1.529334 12.115038)
			(stroke
				(width 0.1524)
				(type default)
			)
			(layer "F.SilkS")
		)
		(fp_line
			(start 3.074924 12.014962)
			(end 1.632204 12.014962)
			(stroke
				(width 0.1524)
				(type default)
			)
			(layer "F.SilkS")
		)
		(fp_line
			(start 1.632204 -12.014962)
			(end 3.074924 -12.014962)
			(stroke
				(width 0.1524)
				(type default)
			)
			(layer "F.SilkS")
		)
		(fp_line
			(start 1.529334 -12.115038)
			(end 3.150108 -12.115038)
			(stroke
				(width 0.1524)
				(type default)
			)
			(layer "F.SilkS")
		)
		(fp_line
			(start -1.529334 12.115038)
			(end -3.150108 12.115038)
			(stroke
				(width 0.1524)
				(type default)
			)
			(layer "F.SilkS")
		)
		(fp_line
			(start -1.632204 12.014962)
			(end -3.074924 12.014962)
			(stroke
				(width 0.1524)
				(type default)
			)
			(layer "F.SilkS")
		)
		(fp_line
			(start -3.074924 -12.014962)
			(end -1.632204 -12.014962)
			(stroke
				(width 0.1524)
				(type default)
			)
			(layer "F.SilkS")
		)
		(fp_line
			(start -3.150108 -12.115038)
			(end -1.529334 -12.115038)
			(stroke
				(width 0.1524)
				(type default)
			)
			(layer "F.SilkS")
		)
		(fp_poly
			(pts
				(xy 3.291078 -8.609584) (xy 3.71348 -9.877298) (xy 4.558538 -9.03224)
			)
			(stroke
				(width 0)
				(type default)
			)
			(fill yes)
			(layer "F.SilkS")
		)
		(fp_line
			(start 3.074924 12.014962)
			(end -3.074924 12.014962)
			(stroke
				(width 0.1)
				(type default)
			)
			(layer "F.Fab")
		)
		(fp_line
			(start 3.074924 -12.014962)
			(end 3.074924 12.014962)
			(stroke
				(width 0.1)
				(type default)
			)
			(layer "F.Fab")
		)
		(fp_line
			(start -3.074924 12.014962)
			(end -3.074924 -12.014962)
			(stroke
				(width 0.1)
				(type default)
			)
			(layer "F.Fab")
		)
		(fp_line
			(start -3.074924 -12.014962)
			(end 3.074924 -12.014962)
			(stroke
				(width 0.1)
				(type default)
			)
			(layer "F.Fab")
		)
		(fp_poly
			(pts
				(xy 3.348736 -7.994904) (xy 4.543806 -8.592566) (xy 4.543806 -7.397496)
			)
			(stroke
				(width 0)
				(type default)
			)
			(fill yes)
			(layer "F.Fab")
		)
		(pad "" np_thru_hole circle
			(at -1.75006 -9.815068 90)
			(size 1.1176 1.1176)
			(drill 1.1176)
			(layers "*.Cu" "*.Mask")
			(clearance 0.381)
			(thermal_gap 0.381)
		)
		(pad "" np_thru_hole circle
			(at 0 9.815068 90)
			(size 1.1176 1.1176)
			(drill 1.1176)
			(layers "*.Cu" "*.Mask")
			(clearance 0.381)
			(thermal_gap 0.381)
		)
		(pad "A1" smd rect
			(at 2.29997 -7.994904 90)
			(size 0.381 1.27)
			(layers "F.Cu" "F.Mask" "F.Paste")
			(net "GND")
		)
		(pad "A2" smd rect
			(at 2.29997 -7.394956 90)
			(size 0.381 1.27)
			(layers "F.Cu" "F.Mask" "F.Paste")
			(net "GND")
		)
		(pad "A3" smd rect
			(at 2.29997 -6.795008 90)
			(size 0.381 1.27)
			(layers "F.Cu" "F.Mask" "F.Paste")
			(net "GND")
		)
		(pad "A4" smd rect
			(at 2.29997 -6.19506 90)
			(size 0.381 1.27)
			(layers "F.Cu" "F.Mask" "F.Paste")
			(net "GND")
		)
		(pad "A5" smd rect
			(at 2.29997 -5.595112 90)
			(size 0.381 1.27)
			(layers "F.Cu" "F.Mask" "F.Paste")
			(net "GND")
		)
		(pad "A6" smd rect
			(at 2.29997 -4.99491 90)
			(size 0.381 1.27)
			(layers "F.Cu" "F.Mask" "F.Paste")
			(net "GND")
		)
		(pad "A7" smd rect
			(at 2.29997 -4.394962 90)
			(size 0.381 1.27)
			(layers "F.Cu" "F.Mask" "F.Paste")
			(net "SMB_ISO_SSD1_R_SCL")
		)
		(pad "A8" smd rect
			(at 2.29997 -3.795014 90)
			(size 0.381 1.27)
			(layers "F.Cu" "F.Mask" "F.Paste")
			(net "SMB_ISO_SSD1_R_SDA")
		)
		(pad "A9" smd rect
			(at 2.29997 -3.195066 90)
			(size 0.381 1.27)
			(layers "F.Cu" "F.Mask" "F.Paste")
			(net "RST_SMB_SSD1_ISO_R_N")
		)
		(pad "A10" smd rect
			(at 2.29997 -2.595118 90)
			(size 0.381 1.27)
			(layers "F.Cu" "F.Mask" "F.Paste")
			(net "SSD1_LED_ISO_R_N")
		)
		(pad "A11" smd rect
			(at 2.29997 -1.994916 90)
			(size 0.381 1.27)
			(layers "F.Cu" "F.Mask" "F.Paste")
			(net "PU_CLKREQ1")
		)
		(pad "A12" smd rect
			(at 2.29997 -1.394968 90)
			(size 0.381 1.27)
			(layers "F.Cu" "F.Mask" "F.Paste")
			(net "PRSNT_SSD1_N")
		)
		(pad "A13" smd rect
			(at 2.29997 -0.79502 90)
			(size 0.381 1.27)
			(layers "F.Cu" "F.Mask" "F.Paste")
			(net "GND")
		)
		(pad "A14" smd rect
			(at 2.29997 -0.195072 90)
			(size 0.381 1.27)
			(layers "F.Cu" "F.Mask" "F.Paste")
			(net "Net_8579")
		)
		(pad "A15" smd rect
			(at 2.29997 0.404876 90)
			(size 0.381 1.27)
			(layers "F.Cu" "F.Mask" "F.Paste")
			(net "Net_8578")
		)
		(pad "A16" smd rect
			(at 2.29997 1.005078 90)
			(size 0.381 1.27)
			(layers "F.Cu" "F.Mask" "F.Paste")
			(net "GND")
		)
		(pad "A17" smd rect
			(at 2.29997 1.605026 90)
			(size 0.381 1.27)
			(layers "F.Cu" "F.Mask" "F.Paste")
			(net "P5E_PEX0_STN2_RX_DN<40>")
		)
		(pad "A18" smd rect
			(at 2.29997 2.204974 90)
			(size 0.381 1.27)
			(layers "F.Cu" "F.Mask" "F.Paste")
			(net "P5E_PEX0_STN2_RX_DP<40>")
		)
		(pad "A19" smd rect
			(at 2.29997 2.804922 90)
			(size 0.381 1.27)
			(layers "F.Cu" "F.Mask" "F.Paste")
			(net "GND")
		)
		(pad "A20" smd rect
			(at 2.29997 3.405124 90)
			(size 0.381 1.27)
			(layers "F.Cu" "F.Mask" "F.Paste")
			(net "P5E_PEX0_STN2_RX_DN<41>")
		)
		(pad "A21" smd rect
			(at 2.29997 4.005072 90)
			(size 0.381 1.27)
			(layers "F.Cu" "F.Mask" "F.Paste")
			(net "P5E_PEX0_STN2_RX_DP<41>")
		)
		(pad "A22" smd rect
			(at 2.29997 4.60502 90)
			(size 0.381 1.27)
			(layers "F.Cu" "F.Mask" "F.Paste")
			(net "GND")
		)
		(pad "A23" smd rect
			(at 2.29997 5.204968 90)
			(size 0.381 1.27)
			(layers "F.Cu" "F.Mask" "F.Paste")
			(net "P5E_PEX0_STN2_RX_DN<42>")
		)
		(pad "A24" smd rect
			(at 2.29997 5.804916 90)
			(size 0.381 1.27)
			(layers "F.Cu" "F.Mask" "F.Paste")
			(net "P5E_PEX0_STN2_RX_DP<42>")
		)
		(pad "A25" smd rect
			(at 2.29997 6.405118 90)
			(size 0.381 1.27)
			(layers "F.Cu" "F.Mask" "F.Paste")
			(net "GND")
		)
		(pad "A26" smd rect
			(at 2.29997 7.005066 90)
			(size 0.381 1.27)
			(layers "F.Cu" "F.Mask" "F.Paste")
			(net "P5E_PEX0_STN2_RX_DN<43>")
		)
		(pad "A27" smd rect
			(at 2.29997 7.605014 90)
			(size 0.381 1.27)
			(layers "F.Cu" "F.Mask" "F.Paste")
			(net "P5E_PEX0_STN2_RX_DP<43>")
		)
		(pad "A28" smd rect
			(at 2.29997 8.204962 90)
			(size 0.381 1.27)
			(layers "F.Cu" "F.Mask" "F.Paste")
			(net "GND")
		)
		(pad "B1" smd rect
			(at -2.29997 -7.994904 90)
			(size 0.381 1.27)
			(layers "F.Cu" "F.Mask" "F.Paste")
			(net "P12V_SSD1")
		)
		(pad "B2" smd rect
			(at -2.29997 -7.394956 90)
			(size 0.381 1.27)
			(layers "F.Cu" "F.Mask" "F.Paste")
			(net "P12V_SSD1")
		)
		(pad "B3" smd rect
			(at -2.29997 -6.795008 90)
			(size 0.381 1.27)
			(layers "F.Cu" "F.Mask" "F.Paste")
			(net "P12V_SSD1")
		)
		(pad "B4" smd rect
			(at -2.29997 -6.19506 90)
			(size 0.381 1.27)
			(layers "F.Cu" "F.Mask" "F.Paste")
			(net "P12V_SSD1")
		)
		(pad "B5" smd rect
			(at -2.29997 -5.595112 90)
			(size 0.381 1.27)
			(layers "F.Cu" "F.Mask" "F.Paste")
			(net "P12V_SSD1")
		)
		(pad "B6" smd rect
			(at -2.29997 -4.99491 90)
			(size 0.381 1.27)
			(layers "F.Cu" "F.Mask" "F.Paste")
			(net "P12V_SSD1")
		)
		(pad "B7" smd rect
			(at -2.29997 -4.394962 90)
			(size 0.381 1.27)
			(layers "F.Cu" "F.Mask" "F.Paste")
			(net "Net_8580")
		)
		(pad "B8" smd rect
			(at -2.29997 -3.795014 90)
			(size 0.381 1.27)
			(layers "F.Cu" "F.Mask" "F.Paste")
			(net "Net_8577")
		)
		(pad "B9" smd rect
			(at -2.29997 -3.195066 90)
			(size 0.381 1.27)
			(layers "F.Cu" "F.Mask" "F.Paste")
			(net "DUALPORT_N_SSD1")
		)
		(pad "B10" smd rect
			(at -2.29997 -2.595118 90)
			(size 0.381 1.27)
			(layers "F.Cu" "F.Mask" "F.Paste")
			(net "RST_SSD1_PERST_R_N")
		)
		(pad "B11" smd rect
			(at -2.29997 -1.994916 90)
			(size 0.381 1.27)
			(layers "F.Cu" "F.Mask" "F.Paste")
			(net "P3V3_SSD1")
		)
		(pad "B12" smd rect
			(at -2.29997 -1.394968 90)
			(size 0.381 1.27)
			(layers "F.Cu" "F.Mask" "F.Paste")
			(net "SSD1_PWRDIS_R")
		)
		(pad "B13" smd rect
			(at -2.29997 -0.79502 90)
			(size 0.381 1.27)
			(layers "F.Cu" "F.Mask" "F.Paste")
			(net "GND")
		)
		(pad "B14" smd rect
			(at -2.29997 -0.195072 90)
			(size 0.381 1.27)
			(layers "F.Cu" "F.Mask" "F.Paste")
			(net "CLK_100M_DB800ZL_SSD1_R_DN")
		)
		(pad "B15" smd rect
			(at -2.29997 0.404876 90)
			(size 0.381 1.27)
			(layers "F.Cu" "F.Mask" "F.Paste")
			(net "CLK_100M_DB800ZL_SSD1_R_DP")
		)
		(pad "B16" smd rect
			(at -2.29997 1.005078 90)
			(size 0.381 1.27)
			(layers "F.Cu" "F.Mask" "F.Paste")
			(net "GND")
		)
		(pad "B17" smd rect
			(at -2.29997 1.605026 90)
			(size 0.381 1.27)
			(layers "F.Cu" "F.Mask" "F.Paste")
			(net "P5E_PEX0_STN2_TX_C_DN<40>")
		)
		(pad "B18" smd rect
			(at -2.29997 2.204974 90)
			(size 0.381 1.27)
			(layers "F.Cu" "F.Mask" "F.Paste")
			(net "P5E_PEX0_STN2_TX_C_DP<40>")
		)
		(pad "B19" smd rect
			(at -2.29997 2.804922 90)
			(size 0.381 1.27)
			(layers "F.Cu" "F.Mask" "F.Paste")
			(net "GND")
		)
		(pad "B20" smd rect
			(at -2.29997 3.405124 90)
			(size 0.381 1.27)
			(layers "F.Cu" "F.Mask" "F.Paste")
			(net "P5E_PEX0_STN2_TX_C_DN<41>")
		)
		(pad "B21" smd rect
			(at -2.29997 4.005072 90)
			(size 0.381 1.27)
			(layers "F.Cu" "F.Mask" "F.Paste")
			(net "P5E_PEX0_STN2_TX_C_DP<41>")
		)
		(pad "B22" smd rect
			(at -2.29997 4.60502 90)
			(size 0.381 1.27)
			(layers "F.Cu" "F.Mask" "F.Paste")
			(net "GND")
		)
		(pad "B23" smd rect
			(at -2.29997 5.204968 90)
			(size 0.381 1.27)
			(layers "F.Cu" "F.Mask" "F.Paste")
			(net "P5E_PEX0_STN2_TX_C_DN<42>")
		)
		(pad "B24" smd rect
			(at -2.29997 5.804916 90)
			(size 0.381 1.27)
			(layers "F.Cu" "F.Mask" "F.Paste")
			(net "P5E_PEX0_STN2_TX_C_DP<42>")
		)
		(pad "B25" smd rect
			(at -2.29997 6.405118 90)
			(size 0.381 1.27)
			(layers "F.Cu" "F.Mask" "F.Paste")
			(net "GND")
		)
		(pad "B26" smd rect
			(at -2.29997 7.005066 90)
			(size 0.381 1.27)
			(layers "F.Cu" "F.Mask" "F.Paste")
			(net "P5E_PEX0_STN2_TX_C_DN<43>")
		)
		(pad "B27" smd rect
			(at -2.29997 7.605014 90)
			(size 0.381 1.27)
			(layers "F.Cu" "F.Mask" "F.Paste")
			(net "P5E_PEX0_STN2_TX_C_DP<43>")
		)
		(pad "B28" smd rect
			(at -2.29997 8.204962 90)
			(size 0.381 1.27)
			(layers "F.Cu" "F.Mask" "F.Paste")
			(net "GND")
		)
		(pad "G1" thru_hole oval
			(at 0 -11.364976 90)
			(size 1.6256 3.4798)
			(drill oval 1.1176 2.4638)
			(layers "*.Cu" "*.Mask")
			(remove_unused_layers no)
			(net "GND")
			(clearance 0.127)
			(thermal_gap 0.127)
		)
		(pad "G2" thru_hole oval
			(at 0 11.364976 90)
			(size 1.6256 3.4798)
			(drill oval 1.1176 2.4638)
			(layers "*.Cu" "*.Mask")
			(remove_unused_layers no)
			(net "GND")
			(clearance 0.127)
			(thermal_gap 0.127)
		)
		(zone
			(layer "F.Cu")
			(hatch none 0.5)
			(connect_pads
				(clearance 0)
			)
			(min_thickness 0.25)
			(keepout
				(tracks not_allowed)
				(vias allowed)
				(pads allowed)
				(copperpour not_allowed)
				(footprints allowed)
			)
			(placement
				(enabled no)
				(sheetname "")
			)
			(fill
				(thermal_gap 0.5)
				(thermal_bridge_width 0.5)
				(island_removal_mode 0)
			)
			(polygon
				(pts
					(xy 40.344852 -38.850062) (xy 37.594794 -38.850062) (xy 37.594794 -35.900106) (xy 40.344852 -35.900106)
				)
			)
		)
		(zone
			(layer "F.Cu")
			(hatch none 0.5)
			(connect_pads
				(clearance 0)
			)
			(min_thickness 0.25)
			(keepout
				(tracks not_allowed)
				(vias allowed)
				(pads allowed)
				(copperpour not_allowed)
				(footprints allowed)
			)
			(placement
				(enabled no)
				(sheetname "")
			)
			(fill
				(thermal_gap 0.5)
				(thermal_bridge_width 0.5)
				(island_removal_mode 0)
			)
			(polygon
				(pts
					(xy 41.414954 -17.670018) (xy 37.584888 -17.670018) (xy 37.584888 -14.720062) (xy 41.414954 -14.720062)
				)
			)
		)
		(zone
			(layers "F.Cu" "B.Cu" "In1.Cu" "In2.Cu" "In3.Cu" "In4.Cu" "In5.Cu" "In6.Cu"
				"In7.Cu" "In8.Cu" "In9.Cu" "In10.Cu" "In11.Cu" "In12.Cu" "In13.Cu" "In14.Cu"
				"In15.Cu" "In16.Cu"
			)
			(hatch none 0.5)
			(connect_pads
				(clearance 0)
			)
			(min_thickness 0.25)
			(keepout
				(tracks not_allowed)
				(vias allowed)
				(pads allowed)
				(copperpour not_allowed)
				(footprints allowed)
			)
			(placement
				(enabled no)
				(sheetname "")
			)
			(fill
				(thermal_gap 0.5)
				(thermal_bridge_width 0.5)
				(island_removal_mode 0)
			)
			(polygon
				(pts
					(arc
						(start 39.93007 -36.60013)
						(mid 37.99967 -36.60013)
						(end 39.93007 -36.60013)
					)
				)
			)
		)
		(zone
			(layers "F.Cu" "B.Cu" "In1.Cu" "In2.Cu" "In3.Cu" "In4.Cu" "In5.Cu" "In6.Cu"
				"In7.Cu" "In8.Cu" "In9.Cu" "In10.Cu" "In11.Cu" "In12.Cu" "In13.Cu" "In14.Cu"
				"In15.Cu" "In16.Cu"
			)
			(hatch none 0.5)
			(connect_pads
				(clearance 0)
			)
			(min_thickness 0.25)
			(keepout
				(tracks not_allowed)
				(vias allowed)
				(pads allowed)
				(copperpour not_allowed)
				(footprints allowed)
			)
			(placement
				(enabled no)
				(sheetname "")
			)
			(fill
				(thermal_gap 0.5)
				(thermal_bridge_width 0.5)
				(island_removal_mode 0)
			)
			(polygon
				(pts
					(arc
						(start 41.68013 -16.969994)
						(mid 39.74973 -16.969994)
						(end 41.68013 -16.969994)
					)
				)
			)
		)
	)
)
